(kicad_pcb
	(version 20260206)
	(generator "pcbnew")
	(generator_version "10.0")
	(general
		(thickness 1.6)
		(legacy_teardrops no)
	)
	(paper "A4")
	(title_block
		(title "panther-plus-userver — 13130-1b_20150205.brd")
		(comment 1 "Honey Badger (Wiwynn) / footprints 1234-1241 of 1509")
	)
	(layers
		(0 "F.Cu" signal "TOP")
		(4 "In1.Cu" signal "L2")
		(6 "In2.Cu" signal "L3")
		(8 "In3.Cu" signal "L4")
		(10 "In4.Cu" signal "L5")
		(12 "In5.Cu" signal "L6")
		(14 "In6.Cu" signal "L7")
		(16 "In7.Cu" signal "L8")
		(18 "In8.Cu" signal "L9")
		(20 "In9.Cu" signal "L10")
		(22 "In10.Cu" signal "L11")
		(2 "B.Cu" signal "BOTTOM")
		(9 "F.Adhes" user "F.Adhesive")
		(11 "B.Adhes" user "B.Adhesive")
		(13 "F.Paste" user "Package Geometry/Pastemask Top")
		(15 "B.Paste" user "Package Geometry/Pastemask Bottom")
		(5 "F.SilkS" user "Ref Des/Silkscreen Top")
		(7 "B.SilkS" user "Ref Des/Silkscreen Bottom")
		(1 "F.Mask" user "Board Geometry/Soldermask Top")
		(3 "B.Mask" user "Board Geometry/Soldermask Bottom")
		(17 "Dwgs.User" user "User.Drawings")
		(19 "Cmts.User" user "User.Comments")
		(21 "Eco1.User" user "User.Eco1")
		(23 "Eco2.User" user "User.Eco2")
		(25 "Edge.Cuts" user "Board Geometry/Outline")
		(27 "Margin" user)
		(31 "F.CrtYd" user "Package Geometry/Place Bound Top")
		(29 "B.CrtYd" user "Package Geometry/Place Bound Bottom")
		(35 "F.Fab" user "Ref Des/Assembly Top")
		(33 "B.Fab" user "Ref Des/Assembly Bottom")
	)
	(footprint ""
		(layer "B.Cu")
		(at 102.489 -27.321002)
		(property "Reference" "R373"
			(at 0 0 0)
			(layer "B.SilkS")
			(hide yes)
			(effects
				(font
					(size 1.27 1.27)
				)
				(justify mirror)
			)
		)
		(property "Value" "100R2F-L1-GP-U"
			(at -0.064008 -3.993896 0)
			(unlocked yes)
			(layer "B.Fab")
			(hide yes)
			(effects
				(font
					(size 1.016 1.016)
					(thickness 0.1524)
				)
				(justify mirror)
			)
		)
		(property "Device Type" "R402H14"
			(at -0.064008 -5.517896 0)
			(unlocked yes)
			(layer "B.Fab")
			(hide yes)
			(effects
				(font
					(size 1.016 1.016)
					(thickness 0.1524)
				)
				(justify mirror)
			)
		)
		(duplicate_pad_numbers_are_jumpers no)
		(fp_rect
			(start 0.381 0.8382)
			(end -0.381 -0.8382)
			(stroke
				(width 0)
				(type default)
			)
			(fill no)
			(layer "B.CrtYd")
		)
		(fp_rect
			(start 0.381 0.8382)
			(end -0.381 -0.8382)
			(stroke
				(width 0)
				(type default)
			)
			(fill no)
			(layer "B.Fab")
		)
		(pad "1" smd custom
			(at 0 -0.4318 180)
			(size 0.127 0.127)
			(layers "B.Cu" "B.Mask" "B.Paste")
			(net "PV_VDDR")
			(options
				(clearance outline)
				(anchor circle)
			)
			(primitives
				(gr_poly
					(pts
						(arc
							(start -0.2032 0.2794)
							(mid -0.239121 0.264521)
							(end -0.254 0.2286)
						)
						(arc
							(start -0.254 -0.2286)
							(mid -0.239121 -0.264521)
							(end -0.2032 -0.2794)
						)
						(arc
							(start 0.2032 -0.2794)
							(mid 0.239121 -0.264521)
							(end 0.254 -0.2286)
						)
						(arc
							(start 0.254 0.2286)
							(mid 0.239121 0.264521)
							(end 0.2032 0.2794)
						)
					)
					(width 0)
					(fill yes)
				)
			)
		)
		(pad "2" smd custom
			(at 0 0.4318 180)
			(size 0.127 0.127)
			(layers "B.Cu" "B.Mask" "B.Paste")
			(net "M_B_VREF")
			(options
				(clearance outline)
				(anchor circle)
			)
			(primitives
				(gr_poly
					(pts
						(arc
							(start -0.2032 0.2794)
							(mid -0.239121 0.264521)
							(end -0.254 0.2286)
						)
						(arc
							(start -0.254 -0.2286)
							(mid -0.239121 -0.264521)
							(end -0.2032 -0.2794)
						)
						(arc
							(start 0.2032 -0.2794)
							(mid 0.239121 -0.264521)
							(end 0.254 -0.2286)
						)
						(arc
							(start 0.254 0.2286)
							(mid 0.239121 0.264521)
							(end 0.2032 0.2794)
						)
					)
					(width 0)
					(fill yes)
				)
			)
		)
	)
	(footprint ""
		(layer "B.Cu")
		(at 86.106 -21.463 90)
		(property "Reference" "PR223"
			(at 0 0 90)
			(layer "B.SilkS")
			(hide yes)
			(effects
				(font
					(size 1.27 1.27)
				)
				(justify mirror)
			)
		)
		(property "Value" "4K75R2F-1-GP"
			(at -0.064008 -3.993896 90)
			(unlocked yes)
			(layer "B.Fab")
			(hide yes)
			(effects
				(font
					(size 1.016 1.016)
					(thickness 0.1524)
				)
				(justify mirror)
			)
		)
		(property "Device Type" "R402H16"
			(at -0.064008 -5.517896 90)
			(unlocked yes)
			(layer "B.Fab")
			(hide yes)
			(effects
				(font
					(size 1.016 1.016)
					(thickness 0.1524)
				)
				(justify mirror)
			)
		)
		(duplicate_pad_numbers_are_jumpers no)
		(fp_rect
			(start 0.381 0.8382)
			(end -0.381 -0.8382)
			(stroke
				(width 0)
				(type default)
			)
			(fill no)
			(layer "B.CrtYd")
		)
		(fp_rect
			(start 0.381 0.8382)
			(end -0.381 -0.8382)
			(stroke
				(width 0)
				(type default)
			)
			(fill no)
			(layer "B.Fab")
		)
		(pad "1" smd custom
			(at 0 -0.4318 270)
			(size 0.127 0.127)
			(layers "B.Cu" "B.Mask" "B.Paste")
			(net "TPS74801_1V35_FB")
			(options
				(clearance outline)
				(anchor circle)
			)
			(primitives
				(gr_poly
					(pts
						(arc
							(start -0.2032 0.2794)
							(mid -0.239121 0.264521)
							(end -0.254 0.2286)
						)
						(arc
							(start -0.254 -0.2286)
							(mid -0.239121 -0.264521)
							(end -0.2032 -0.2794)
						)
						(arc
							(start 0.2032 -0.2794)
							(mid 0.239121 -0.264521)
							(end 0.254 -0.2286)
						)
						(arc
							(start 0.254 0.2286)
							(mid 0.239121 0.264521)
							(end 0.2032 0.2794)
						)
					)
					(width 0)
					(fill yes)
				)
			)
		)
		(pad "2" smd custom
			(at 0 0.4318 270)
			(size 0.127 0.127)
			(layers "B.Cu" "B.Mask" "B.Paste")
			(net "GND")
			(options
				(clearance outline)
				(anchor circle)
			)
			(primitives
				(gr_poly
					(pts
						(arc
							(start -0.2032 0.2794)
							(mid -0.239121 0.264521)
							(end -0.254 0.2286)
						)
						(arc
							(start -0.254 -0.2286)
							(mid -0.239121 -0.264521)
							(end -0.2032 -0.2794)
						)
						(arc
							(start 0.2032 -0.2794)
							(mid 0.239121 -0.264521)
							(end 0.254 -0.2286)
						)
						(arc
							(start 0.254 0.2286)
							(mid 0.239121 0.264521)
							(end 0.2032 0.2794)
						)
					)
					(width 0)
					(fill yes)
				)
			)
		)
	)
	(footprint ""
		(layer "B.Cu")
		(at 187.071 -11.812778 -90)
		(property "Reference" "R195"
			(at 0 0 90)
			(layer "B.SilkS")
			(hide yes)
			(effects
				(font
					(size 1.27 1.27)
				)
				(justify mirror)
			)
		)
		(property "Value" "4K7R2F-GP"
			(at -0.064008 -3.993896 270)
			(unlocked yes)
			(layer "B.Fab")
			(hide yes)
			(effects
				(font
					(size 1.016 1.016)
					(thickness 0.1524)
				)
				(justify mirror)
			)
		)
		(property "Device Type" "R402H16"
			(at -0.064008 -5.517896 270)
			(unlocked yes)
			(layer "B.Fab")
			(hide yes)
			(effects
				(font
					(size 1.016 1.016)
					(thickness 0.1524)
				)
				(justify mirror)
			)
		)
		(duplicate_pad_numbers_are_jumpers no)
		(fp_rect
			(start 0.381 0.8382)
			(end -0.381 -0.8382)
			(stroke
				(width 0)
				(type default)
			)
			(fill no)
			(layer "B.CrtYd")
		)
		(fp_rect
			(start 0.381 0.8382)
			(end -0.381 -0.8382)
			(stroke
				(width 0)
				(type default)
			)
			(fill no)
			(layer "B.Fab")
		)
		(pad "1" smd custom
			(at 0 -0.4318 90)
			(size 0.127 0.127)
			(layers "B.Cu" "B.Mask" "B.Paste")
			(net "CHB_0_SA0")
			(options
				(clearance outline)
				(anchor circle)
			)
			(primitives
				(gr_poly
					(pts
						(arc
							(start -0.2032 0.2794)
							(mid -0.239121 0.264521)
							(end -0.254 0.2286)
						)
						(arc
							(start -0.254 -0.2286)
							(mid -0.239121 -0.264521)
							(end -0.2032 -0.2794)
						)
						(arc
							(start 0.2032 -0.2794)
							(mid 0.239121 -0.264521)
							(end 0.254 -0.2286)
						)
						(arc
							(start 0.254 0.2286)
							(mid 0.239121 0.264521)
							(end 0.2032 0.2794)
						)
					)
					(width 0)
					(fill yes)
				)
			)
		)
		(pad "2" smd custom
			(at 0 0.4318 90)
			(size 0.127 0.127)
			(layers "B.Cu" "B.Mask" "B.Paste")
			(net "GND")
			(options
				(clearance outline)
				(anchor circle)
			)
			(primitives
				(gr_poly
					(pts
						(arc
							(start -0.2032 0.2794)
							(mid -0.239121 0.264521)
							(end -0.254 0.2286)
						)
						(arc
							(start -0.254 -0.2286)
							(mid -0.239121 -0.264521)
							(end -0.2032 -0.2794)
						)
						(arc
							(start 0.2032 -0.2794)
							(mid 0.239121 -0.264521)
							(end 0.254 -0.2286)
						)
						(arc
							(start 0.254 0.2286)
							(mid 0.239121 0.264521)
							(end 0.2032 0.2794)
						)
					)
					(width 0)
					(fill yes)
				)
			)
		)
	)
	(footprint ""
		(layer "B.Cu")
		(at 200.787 -27.559 -90)
		(property "Reference" "PC92"
			(at 0 0 90)
			(layer "B.SilkS")
			(hide yes)
			(effects
				(font
					(size 1.27 1.27)
				)
				(justify mirror)
			)
		)
		(property "Value" "SC22U25V5MX-GP"
			(at 0 -4.9022 270)
			(unlocked yes)
			(layer "B.Fab")
			(hide yes)
			(effects
				(font
					(size 1.016 1.016)
					(thickness 0.1524)
				)
				(justify mirror)
			)
		)
		(property "Device Type" "C805H58"
			(at 0 -6.8072 270)
			(unlocked yes)
			(layer "B.Fab")
			(hide yes)
			(effects
				(font
					(size 1.016 1.016)
					(thickness 0.1524)
				)
				(justify mirror)
			)
		)
		(duplicate_pad_numbers_are_jumpers no)
		(fp_line
			(start -0.6096 0)
			(end 0.6096 0)
			(stroke
				(width 0.3048)
				(type default)
			)
			(layer "B.SilkS")
		)
		(fp_poly
			(pts
				(xy 0.9017 1.4351) (xy -0.9017 1.4351) (xy -0.9017 -1.4351) (xy 0.9017 -1.4351)
			)
			(stroke
				(width 0)
				(type default)
			)
			(fill no)
			(layer "B.CrtYd")
		)
		(fp_poly
			(pts
				(xy -0.9017 1.4351) (xy -0.9017 -1.4351) (xy 0.9017 -1.4351) (xy 0.9017 1.4351)
			)
			(stroke
				(width 0)
				(type default)
			)
			(fill no)
			(layer "B.Fab")
		)
		(pad "1" smd rect
			(at 0 -0.8382 90)
			(size 1.5494 0.9398)
			(layers "B.Cu" "B.Mask" "B.Paste")
			(net "PVDDR_VIN")
		)
		(pad "2" smd rect
			(at 0 0.8382 90)
			(size 1.5494 0.9398)
			(layers "B.Cu" "B.Mask" "B.Paste")
			(net "GND")
		)
	)
	(footprint ""
		(layer "B.Cu")
		(at 92.71 -46.4058 -90)
		(property "Reference" "C150"
			(at 0 0 90)
			(layer "B.SilkS")
			(hide yes)
			(effects
				(font
					(size 1.27 1.27)
				)
				(justify mirror)
			)
		)
		(property "Value" "SC1U10V2KX-1GP"
			(at -1.1811 -2.7051 270)
			(unlocked yes)
			(layer "B.Fab")
			(hide yes)
			(effects
				(font
					(size 1.016 1.016)
					(thickness 0.1524)
				)
				(justify mirror)
			)
		)
		(property "Device Type" "C402H22"
			(at -1.1811 -4.2291 270)
			(unlocked yes)
			(layer "B.Fab")
			(hide yes)
			(effects
				(font
					(size 1.016 1.016)
					(thickness 0.1524)
				)
				(justify mirror)
			)
		)
		(duplicate_pad_numbers_are_jumpers no)
		(fp_rect
			(start 0.381 0.7366)
			(end -0.381 -0.7366)
			(stroke
				(width 0)
				(type default)
			)
			(fill no)
			(layer "B.CrtYd")
		)
		(fp_rect
			(start 0.381 0.7366)
			(end -0.381 -0.7366)
			(stroke
				(width 0)
				(type default)
			)
			(fill no)
			(layer "B.Fab")
		)
		(pad "1" smd custom
			(at 0 -0.4572 90)
			(size 0.1143 0.1143)
			(layers "B.Cu" "B.Mask" "B.Paste")
			(net "P1V0")
			(options
				(clearance outline)
				(anchor circle)
			)
			(primitives
				(gr_poly
					(pts
						(arc
							(start -0.254 0.1778)
							(mid -0.239121 0.213721)
							(end -0.2032 0.2286)
						)
						(arc
							(start 0.2032 0.2286)
							(mid 0.239121 0.213721)
							(end 0.254 0.1778)
						)
						(arc
							(start 0.254 -0.1778)
							(mid 0.239121 -0.213721)
							(end 0.2032 -0.2286)
						)
						(arc
							(start -0.2032 -0.2286)
							(mid -0.239121 -0.213721)
							(end -0.254 -0.1778)
						)
					)
					(width 0)
					(fill yes)
				)
			)
		)
		(pad "2" smd custom
			(at 0 0.4572 90)
			(size 0.1143 0.1143)
			(layers "B.Cu" "B.Mask" "B.Paste")
			(net "GND")
			(options
				(clearance outline)
				(anchor circle)
			)
			(primitives
				(gr_poly
					(pts
						(arc
							(start -0.254 0.1778)
							(mid -0.239121 0.213721)
							(end -0.2032 0.2286)
						)
						(arc
							(start 0.2032 0.2286)
							(mid 0.239121 0.213721)
							(end 0.254 0.1778)
						)
						(arc
							(start 0.254 -0.1778)
							(mid 0.239121 -0.213721)
							(end 0.2032 -0.2286)
						)
						(arc
							(start -0.2032 -0.2286)
							(mid -0.239121 -0.213721)
							(end -0.254 -0.1778)
						)
					)
					(width 0)
					(fill yes)
				)
			)
		)
	)
	(footprint ""
		(layer "B.Cu")
		(at 202.438 -44.704 180)
		(property "Reference" "PC69"
			(at 0 0 0)
			(layer "B.SilkS")
			(hide yes)
			(effects
				(font
					(size 1.27 1.27)
				)
				(justify mirror)
			)
		)
		(property "Value" "SC3300P50V3KX-1GP"
			(at 0.0254 -2.0193 180)
			(unlocked yes)
			(layer "B.Fab")
			(hide yes)
			(effects
				(font
					(size 1.016 1.016)
					(thickness 0.1524)
				)
				(justify mirror)
			)
		)
		(property "Device Type" "C603H36"
			(at 0.0254 -3.5433 180)
			(unlocked yes)
			(layer "B.Fab")
			(hide yes)
			(effects
				(font
					(size 1.016 1.016)
					(thickness 0.1524)
				)
				(justify mirror)
			)
		)
		(duplicate_pad_numbers_are_jumpers no)
		(fp_line
			(start 0.4064 0)
			(end -0.4064 0)
			(stroke
				(width 0.2286)
				(type default)
			)
			(layer "B.SilkS")
		)
		(fp_rect
			(start 0.635 1.1811)
			(end -0.635 -1.1811)
			(stroke
				(width 0)
				(type default)
			)
			(fill no)
			(layer "B.CrtYd")
		)
		(fp_rect
			(start 0.635 1.1811)
			(end -0.635 -1.1811)
			(stroke
				(width 0)
				(type default)
			)
			(fill no)
			(layer "B.Fab")
		)
		(pad "1" smd custom
			(at 0 -0.6604)
			(size 0.19685 0.19685)
			(layers "B.Cu" "B.Mask" "B.Paste")
			(net "VR_PVDDR_A_VSW")
			(options
				(clearance outline)
				(anchor circle)
			)
			(primitives
				(gr_poly
					(pts
						(arc
							(start 0.508 0.2921)
							(mid 0.478242 0.363942)
							(end 0.4064 0.3937)
						)
						(arc
							(start -0.4064 0.3937)
							(mid -0.478242 0.363942)
							(end -0.508 0.2921)
						)
						(arc
							(start -0.508 -0.2921)
							(mid -0.478242 -0.363942)
							(end -0.4064 -0.3937)
						)
						(arc
							(start 0.4064 -0.3937)
							(mid 0.478242 -0.363942)
							(end 0.508 -0.2921)
						)
					)
					(width 0)
					(fill yes)
				)
			)
		)
		(pad "2" smd custom
			(at 0 0.6604)
			(size 0.19685 0.19685)
			(layers "B.Cu" "B.Mask" "B.Paste")
			(net "VR_PVDDR_A_VSW_R")
			(options
				(clearance outline)
				(anchor circle)
			)
			(primitives
				(gr_poly
					(pts
						(arc
							(start 0.508 0.2921)
							(mid 0.478242 0.363942)
							(end 0.4064 0.3937)
						)
						(arc
							(start -0.4064 0.3937)
							(mid -0.478242 0.363942)
							(end -0.508 0.2921)
						)
						(arc
							(start -0.508 -0.2921)
							(mid -0.478242 -0.363942)
							(end -0.4064 -0.3937)
						)
						(arc
							(start 0.4064 -0.3937)
							(mid 0.478242 -0.363942)
							(end 0.508 -0.2921)
						)
					)
					(width 0)
					(fill yes)
				)
			)
		)
	)
	(footprint ""
		(layer "B.Cu")
		(at 70.4596 -45.593 180)
		(property "Reference" "R295"
			(at 0 0 0)
			(layer "B.SilkS")
			(hide yes)
			(effects
				(font
					(size 1.27 1.27)
				)
				(justify mirror)
			)
		)
		(property "Value" "10KR2F-2-GP"
			(at -0.064008 -3.993896 180)
			(unlocked yes)
			(layer "B.Fab")
			(hide yes)
			(effects
				(font
					(size 1.016 1.016)
					(thickness 0.1524)
				)
				(justify mirror)
			)
		)
		(property "Device Type" "R402H16"
			(at -0.064008 -5.517896 180)
			(unlocked yes)
			(layer "B.Fab")
			(hide yes)
			(effects
				(font
					(size 1.016 1.016)
					(thickness 0.1524)
				)
				(justify mirror)
			)
		)
		(duplicate_pad_numbers_are_jumpers no)
		(fp_rect
			(start 0.381 0.8382)
			(end -0.381 -0.8382)
			(stroke
				(width 0)
				(type default)
			)
			(fill no)
			(layer "B.CrtYd")
		)
		(fp_rect
			(start 0.381 0.8382)
			(end -0.381 -0.8382)
			(stroke
				(width 0)
				(type default)
			)
			(fill no)
			(layer "B.Fab")
		)
		(pad "1" smd custom
			(at 0 -0.4318)
			(size 0.127 0.127)
			(layers "B.Cu" "B.Mask" "B.Paste")
			(net "P3V3")
			(options
				(clearance outline)
				(anchor circle)
			)
			(primitives
				(gr_poly
					(pts
						(arc
							(start -0.2032 0.2794)
							(mid -0.239121 0.264521)
							(end -0.254 0.2286)
						)
						(arc
							(start -0.254 -0.2286)
							(mid -0.239121 -0.264521)
							(end -0.2032 -0.2794)
						)
						(arc
							(start 0.2032 -0.2794)
							(mid 0.239121 -0.264521)
							(end 0.254 -0.2286)
						)
						(arc
							(start 0.254 0.2286)
							(mid 0.239121 0.264521)
							(end 0.2032 0.2794)
						)
					)
					(width 0)
					(fill yes)
				)
			)
		)
		(pad "2" smd custom
			(at 0 0.4318)
			(size 0.127 0.127)
			(layers "B.Cu" "B.Mask" "B.Paste")
			(net "IRQ_NMI_R")
			(options
				(clearance outline)
				(anchor circle)
			)
			(primitives
				(gr_poly
					(pts
						(arc
							(start -0.2032 0.2794)
							(mid -0.239121 0.264521)
							(end -0.254 0.2286)
						)
						(arc
							(start -0.254 -0.2286)
							(mid -0.239121 -0.264521)
							(end -0.2032 -0.2794)
						)
						(arc
							(start 0.2032 -0.2794)
							(mid 0.239121 -0.264521)
							(end 0.254 -0.2286)
						)
						(arc
							(start 0.254 0.2286)
							(mid 0.239121 0.264521)
							(end 0.2032 0.2794)
						)
					)
					(width 0)
					(fill yes)
				)
			)
		)
	)
	(footprint ""
		(layer "B.Cu")
		(at 17.145 -48.133)
		(property "Reference" "C247"
			(at 0 0 0)
			(layer "B.SilkS")
			(hide yes)
			(effects
				(font
					(size 1.27 1.27)
				)
				(justify mirror)
			)
		)
		(property "Value" "SC1U6D3V2KX-GP"
			(at -1.8923 -1.2065 0)
			(unlocked yes)
			(layer "B.Fab")
			(hide yes)
			(effects
				(font
					(size 1.016 1.016)
					(thickness 0.1524)
				)
				(justify mirror)
			)
		)
		(property "Device Type" "C402H22"
			(at -1.8923 -2.7305 0)
			(unlocked yes)
			(layer "B.Fab")
			(hide yes)
			(effects
				(font
					(size 1.016 1.016)
					(thickness 0.1524)
				)
				(justify mirror)
			)
		)
		(duplicate_pad_numbers_are_jumpers no)
		(fp_rect
			(start 0.381 0.7366)
			(end -0.381 -0.7366)
			(stroke
				(width 0)
				(type default)
			)
			(fill no)
			(layer "B.CrtYd")
		)
		(fp_rect
			(start 0.381 0.7366)
			(end -0.381 -0.7366)
			(stroke
				(width 0)
				(type default)
			)
			(fill no)
			(layer "B.Fab")
		)
		(pad "1" smd custom
			(at 0 -0.4572 180)
			(size 0.1143 0.1143)
			(layers "B.Cu" "B.Mask" "B.Paste")
			(net "P3V3")
			(options
				(clearance outline)
				(anchor circle)
			)
			(primitives
				(gr_poly
					(pts
						(arc
							(start -0.254 0.1778)
							(mid -0.239121 0.213721)
							(end -0.2032 0.2286)
						)
						(arc
							(start 0.2032 0.2286)
							(mid 0.239121 0.213721)
							(end 0.254 0.1778)
						)
						(arc
							(start 0.254 -0.1778)
							(mid 0.239121 -0.213721)
							(end 0.2032 -0.2286)
						)
						(arc
							(start -0.2032 -0.2286)
							(mid -0.239121 -0.213721)
							(end -0.254 -0.1778)
						)
					)
					(width 0)
					(fill yes)
				)
			)
		)
		(pad "2" smd custom
			(at 0 0.4572 180)
			(size 0.1143 0.1143)
			(layers "B.Cu" "B.Mask" "B.Paste")
			(net "GND")
			(options
				(clearance outline)
				(anchor circle)
			)
			(primitives
				(gr_poly
					(pts
						(arc
							(start -0.254 0.1778)
							(mid -0.239121 0.213721)
							(end -0.2032 0.2286)
						)
						(arc
							(start 0.2032 0.2286)
							(mid 0.239121 0.213721)
							(end 0.254 0.1778)
						)
						(arc
							(start 0.254 -0.1778)
							(mid 0.239121 -0.213721)
							(end 0.2032 -0.2286)
						)
						(arc
							(start -0.2032 -0.2286)
							(mid -0.239121 -0.213721)
							(end -0.254 -0.1778)
						)
					)
					(width 0)
					(fill yes)
				)
			)
		)
	)
)
